(kicad_pcb
	(version 20260206)
	(generator "pcbnew")
	(generator_version "10.0")
	(general
		(thickness 1.6)
		(legacy_teardrops no)
	)
	(paper "A4")
	(title_block
		(title "Bryce Canyon_F.DPB_16315-1-OCP.brd")
		(comment 1 "Bryce Canyon / footprint 993 of 2223 (SAS1), pads 212-290 of 342")
	)
	(layers
		(0 "F.Cu" signal "TOP")
		(4 "In1.Cu" signal "L2GND")
		(6 "In2.Cu" signal "L3")
		(8 "In3.Cu" signal "L4GND")
		(10 "In4.Cu" signal "L5")
		(12 "In5.Cu" signal "L6VCC")
		(14 "In6.Cu" signal "L7VCC")
		(16 "In7.Cu" signal "L8")
		(18 "In8.Cu" signal "L9GND")
		(20 "In9.Cu" signal "L10")
		(22 "In10.Cu" signal "L11GND")
		(2 "B.Cu" signal "BOTTOM")
		(9 "F.Adhes" user "F.Adhesive")
		(11 "B.Adhes" user "B.Adhesive")
		(13 "F.Paste" user "Package Geometry/Pastemask Top")
		(15 "B.Paste" user "Package Geometry/Pastemask Bottom")
		(5 "F.SilkS" user "Ref Des/Silkscreen Top")
		(7 "B.SilkS" user "Ref Des/Silkscreen Bottom")
		(1 "F.Mask" user "Board Geometry/Soldermask Top")
		(3 "B.Mask" user "Board Geometry/Soldermask Bottom")
		(17 "Dwgs.User" user "User.Drawings")
		(19 "Cmts.User" user "User.Comments")
		(21 "Eco1.User" user "User.Eco1")
		(23 "Eco2.User" user "User.Eco2")
		(25 "Edge.Cuts" user "Board Geometry/Outline")
		(27 "Margin" user)
		(31 "F.CrtYd" user "Package Geometry/Place Bound Top")
		(29 "B.CrtYd" user "Package Geometry/Place Bound Bottom")
		(35 "F.Fab" user "Ref Des/Assembly Top")
		(33 "B.Fab" user "Ref Des/Assembly Bottom")
	)
	(footprint ""
		(layer "F.Cu")
		(at 287.83661 -357.705152 -90)
		(property "Reference" "SAS1"
			(at 0 0 270)
			(layer "F.SilkS")
			(hide yes)
			(effects
				(font
					(size 1.27 1.27)
				)
			)
		)
		(property "Value" "AMP-CONN342-10R-2-GP"
			(at 20.955 -16.7386 270)
			(unlocked yes)
			(layer "F.Fab")
			(hide yes)
			(effects
				(font
					(size 1.016 1.016)
					(thickness 0.1524)
				)
			)
		)
		(property "Device Type" "PREFIT-342P-668151H483"
			(at 20.955 -18.2626 270)
			(unlocked yes)
			(layer "F.Fab")
			(hide yes)
			(effects
				(font
					(size 1.016 1.016)
					(thickness 0.1524)
				)
			)
		)
		(duplicate_pad_numbers_are_jumpers no)
		(pad "F32" thru_hole circle
			(at 55.79999 9.59993 270)
			(size 0.762 0.762)
			(drill 0.359918)
			(layers "*.Cu" "*.Mask")
			(remove_unused_layers no)
			(net "PHY_SCC_A_TO_DRV_A_34_DN")
			(clearance 0.1651)
			(thermal_gap 0.1651)
		)
		(pad "F33" thru_hole circle
			(at 57.600088 8.599932 270)
			(size 0.762 0.762)
			(drill 0.359918)
			(layers "*.Cu" "*.Mask")
			(remove_unused_layers no)
			(net "PHY_SCC_A_TO_DRV_A_33_DN")
			(clearance 0.1651)
			(thermal_gap 0.1651)
		)
		(pad "F34" thru_hole circle
			(at 59.399932 9.59993 270)
			(size 0.762 0.762)
			(drill 0.359918)
			(layers "*.Cu" "*.Mask")
			(remove_unused_layers no)
			(net "PHY_SCC_A_TO_DRV_A_32_DN")
			(clearance 0.1651)
			(thermal_gap 0.1651)
		)
		(pad "F35" thru_hole circle
			(at 61.20003 8.599932 270)
			(size 0.762 0.762)
			(drill 0.359918)
			(layers "*.Cu" "*.Mask")
			(remove_unused_layers no)
			(net "PHY_SCC_A_TO_DRV_A_31_DN")
			(clearance 0.1651)
			(thermal_gap 0.1651)
		)
		(pad "F36" thru_hole circle
			(at 62.999874 9.59993 270)
			(size 0.762 0.762)
			(drill 0.359918)
			(layers "*.Cu" "*.Mask")
			(remove_unused_layers no)
			(net "PHY_SCC_A_TO_DRV_A_30_DN")
			(clearance 0.1651)
			(thermal_gap 0.1651)
		)
		(pad "GND1" thru_hole circle
			(at 0 2.500122 270)
			(size 0.762 0.762)
			(drill 0.359918)
			(layers "*.Cu" "*.Mask")
			(remove_unused_layers no)
			(net "GND")
			(clearance 0.1651)
			(thermal_gap 0.1651)
		)
		(pad "GND2" thru_hole circle
			(at 0 6.100064 270)
			(size 0.762 0.762)
			(drill 0.359918)
			(layers "*.Cu" "*.Mask")
			(remove_unused_layers no)
			(net "GND")
			(clearance 0.1651)
			(thermal_gap 0.1651)
		)
		(pad "GND3" thru_hole circle
			(at 0 9.700006 270)
			(size 0.762 0.762)
			(drill 0.359918)
			(layers "*.Cu" "*.Mask")
			(remove_unused_layers no)
			(net "GND")
			(clearance 0.1651)
			(thermal_gap 0.1651)
		)
		(pad "GND4" thru_hole circle
			(at 1.800098 -0.100076 270)
			(size 0.762 0.762)
			(drill 0.359918)
			(layers "*.Cu" "*.Mask")
			(remove_unused_layers no)
			(net "GND")
			(clearance 0.1651)
			(thermal_gap 0.1651)
		)
		(pad "GND5" thru_hole circle
			(at 1.800098 3.50012 270)
			(size 0.762 0.762)
			(drill 0.359918)
			(layers "*.Cu" "*.Mask")
			(remove_unused_layers no)
			(net "GND")
			(clearance 0.1651)
			(thermal_gap 0.1651)
		)
		(pad "GND6" thru_hole circle
			(at 1.800098 7.100062 270)
			(size 0.762 0.762)
			(drill 0.359918)
			(layers "*.Cu" "*.Mask")
			(remove_unused_layers no)
			(net "GND")
			(clearance 0.1651)
			(thermal_gap 0.1651)
		)
		(pad "GND7" thru_hole circle
			(at 1.800098 10.700004 270)
			(size 0.762 0.762)
			(drill 0.359918)
			(layers "*.Cu" "*.Mask")
			(remove_unused_layers no)
			(net "GND")
			(clearance 0.1651)
			(thermal_gap 0.1651)
		)
		(pad "GND8" thru_hole circle
			(at 3.599942 2.500122 270)
			(size 0.762 0.762)
			(drill 0.359918)
			(layers "*.Cu" "*.Mask")
			(remove_unused_layers no)
			(net "GND")
			(clearance 0.1651)
			(thermal_gap 0.1651)
		)
		(pad "GND9" thru_hole circle
			(at 3.599942 6.100064 270)
			(size 0.762 0.762)
			(drill 0.359918)
			(layers "*.Cu" "*.Mask")
			(remove_unused_layers no)
			(net "GND")
			(clearance 0.1651)
			(thermal_gap 0.1651)
		)
		(pad "GND10" thru_hole circle
			(at 3.599942 9.700006 270)
			(size 0.762 0.762)
			(drill 0.359918)
			(layers "*.Cu" "*.Mask")
			(remove_unused_layers no)
			(net "GND")
			(clearance 0.1651)
			(thermal_gap 0.1651)
		)
		(pad "GND11" thru_hole circle
			(at 5.40004 -0.100076 270)
			(size 0.762 0.762)
			(drill 0.359918)
			(layers "*.Cu" "*.Mask")
			(remove_unused_layers no)
			(net "GND")
			(clearance 0.1651)
			(thermal_gap 0.1651)
		)
		(pad "GND12" thru_hole circle
			(at 5.40004 3.50012 270)
			(size 0.762 0.762)
			(drill 0.359918)
			(layers "*.Cu" "*.Mask")
			(remove_unused_layers no)
			(net "GND")
			(clearance 0.1651)
			(thermal_gap 0.1651)
		)
		(pad "GND13" thru_hole circle
			(at 5.40004 7.100062 270)
			(size 0.762 0.762)
			(drill 0.359918)
			(layers "*.Cu" "*.Mask")
			(remove_unused_layers no)
			(net "GND")
			(clearance 0.1651)
			(thermal_gap 0.1651)
		)
		(pad "GND14" thru_hole circle
			(at 5.40004 10.700004 270)
			(size 0.762 0.762)
			(drill 0.359918)
			(layers "*.Cu" "*.Mask")
			(remove_unused_layers no)
			(net "GND")
			(clearance 0.1651)
			(thermal_gap 0.1651)
		)
		(pad "GND15" thru_hole circle
			(at 7.199884 2.500122 270)
			(size 0.762 0.762)
			(drill 0.359918)
			(layers "*.Cu" "*.Mask")
			(remove_unused_layers no)
			(net "GND")
			(clearance 0.1651)
			(thermal_gap 0.1651)
		)
		(pad "GND16" thru_hole circle
			(at 7.199884 6.100064 270)
			(size 0.762 0.762)
			(drill 0.359918)
			(layers "*.Cu" "*.Mask")
			(remove_unused_layers no)
			(net "GND")
			(clearance 0.1651)
			(thermal_gap 0.1651)
		)
		(pad "GND17" thru_hole circle
			(at 7.199884 9.700006 270)
			(size 0.762 0.762)
			(drill 0.359918)
			(layers "*.Cu" "*.Mask")
			(remove_unused_layers no)
			(net "GND")
			(clearance 0.1651)
			(thermal_gap 0.1651)
		)
		(pad "GND18" thru_hole circle
			(at 8.999982 -0.100076 270)
			(size 0.762 0.762)
			(drill 0.359918)
			(layers "*.Cu" "*.Mask")
			(remove_unused_layers no)
			(net "GND")
			(clearance 0.1651)
			(thermal_gap 0.1651)
		)
		(pad "GND19" thru_hole circle
			(at 8.999982 3.50012 270)
			(size 0.762 0.762)
			(drill 0.359918)
			(layers "*.Cu" "*.Mask")
			(remove_unused_layers no)
			(net "GND")
			(clearance 0.1651)
			(thermal_gap 0.1651)
		)
		(pad "GND20" thru_hole circle
			(at 8.999982 7.100062 270)
			(size 0.762 0.762)
			(drill 0.359918)
			(layers "*.Cu" "*.Mask")
			(remove_unused_layers no)
			(net "GND")
			(clearance 0.1651)
			(thermal_gap 0.1651)
		)
		(pad "GND21" thru_hole circle
			(at 8.999982 10.700004 270)
			(size 0.762 0.762)
			(drill 0.359918)
			(layers "*.Cu" "*.Mask")
			(remove_unused_layers no)
			(net "GND")
			(clearance 0.1651)
			(thermal_gap 0.1651)
		)
		(pad "GND22" thru_hole circle
			(at 10.80008 2.500122 270)
			(size 0.762 0.762)
			(drill 0.359918)
			(layers "*.Cu" "*.Mask")
			(remove_unused_layers no)
			(net "GND")
			(clearance 0.1651)
			(thermal_gap 0.1651)
		)
		(pad "GND23" thru_hole circle
			(at 10.80008 6.100064 270)
			(size 0.762 0.762)
			(drill 0.359918)
			(layers "*.Cu" "*.Mask")
			(remove_unused_layers no)
			(net "GND")
			(clearance 0.1651)
			(thermal_gap 0.1651)
		)
		(pad "GND24" thru_hole circle
			(at 10.80008 9.700006 270)
			(size 0.762 0.762)
			(drill 0.359918)
			(layers "*.Cu" "*.Mask")
			(remove_unused_layers no)
			(net "GND")
			(clearance 0.1651)
			(thermal_gap 0.1651)
		)
		(pad "GND25" thru_hole circle
			(at 12.599924 -0.100076 270)
			(size 0.762 0.762)
			(drill 0.359918)
			(layers "*.Cu" "*.Mask")
			(remove_unused_layers no)
			(net "GND")
			(clearance 0.1651)
			(thermal_gap 0.1651)
		)
		(pad "GND26" thru_hole circle
			(at 12.599924 3.50012 270)
			(size 0.762 0.762)
			(drill 0.359918)
			(layers "*.Cu" "*.Mask")
			(remove_unused_layers no)
			(net "GND")
			(clearance 0.1651)
			(thermal_gap 0.1651)
		)
		(pad "GND27" thru_hole circle
			(at 12.599924 7.100062 270)
			(size 0.762 0.762)
			(drill 0.359918)
			(layers "*.Cu" "*.Mask")
			(remove_unused_layers no)
			(net "GND")
			(clearance 0.1651)
			(thermal_gap 0.1651)
		)
		(pad "GND28" thru_hole circle
			(at 12.599924 10.700004 270)
			(size 0.762 0.762)
			(drill 0.359918)
			(layers "*.Cu" "*.Mask")
			(remove_unused_layers no)
			(net "GND")
			(clearance 0.1651)
			(thermal_gap 0.1651)
		)
		(pad "GND29" thru_hole circle
			(at 14.400022 2.500122 270)
			(size 0.762 0.762)
			(drill 0.359918)
			(layers "*.Cu" "*.Mask")
			(remove_unused_layers no)
			(net "GND")
			(clearance 0.1651)
			(thermal_gap 0.1651)
		)
		(pad "GND30" thru_hole circle
			(at 14.400022 6.100064 270)
			(size 0.762 0.762)
			(drill 0.359918)
			(layers "*.Cu" "*.Mask")
			(remove_unused_layers no)
			(net "GND")
			(clearance 0.1651)
			(thermal_gap 0.1651)
		)
		(pad "GND31" thru_hole circle
			(at 14.400022 9.700006 270)
			(size 0.762 0.762)
			(drill 0.359918)
			(layers "*.Cu" "*.Mask")
			(remove_unused_layers no)
			(net "GND")
			(clearance 0.1651)
			(thermal_gap 0.1651)
		)
		(pad "GND32" thru_hole circle
			(at 16.20012 -0.100076 270)
			(size 0.762 0.762)
			(drill 0.359918)
			(layers "*.Cu" "*.Mask")
			(remove_unused_layers no)
			(net "GND")
			(clearance 0.1651)
			(thermal_gap 0.1651)
		)
		(pad "GND33" thru_hole circle
			(at 16.20012 3.50012 270)
			(size 0.762 0.762)
			(drill 0.359918)
			(layers "*.Cu" "*.Mask")
			(remove_unused_layers no)
			(net "GND")
			(clearance 0.1651)
			(thermal_gap 0.1651)
		)
		(pad "GND34" thru_hole circle
			(at 16.20012 7.100062 270)
			(size 0.762 0.762)
			(drill 0.359918)
			(layers "*.Cu" "*.Mask")
			(remove_unused_layers no)
			(net "GND")
			(clearance 0.1651)
			(thermal_gap 0.1651)
		)
		(pad "GND35" thru_hole circle
			(at 16.20012 10.700004 270)
			(size 0.762 0.762)
			(drill 0.359918)
			(layers "*.Cu" "*.Mask")
			(remove_unused_layers no)
			(net "GND")
			(clearance 0.1651)
			(thermal_gap 0.1651)
		)
		(pad "GND36" thru_hole circle
			(at 17.999964 2.500122 270)
			(size 0.762 0.762)
			(drill 0.359918)
			(layers "*.Cu" "*.Mask")
			(remove_unused_layers no)
			(net "GND")
			(clearance 0.1651)
			(thermal_gap 0.1651)
		)
		(pad "GND37" thru_hole circle
			(at 17.999964 6.100064 270)
			(size 0.762 0.762)
			(drill 0.359918)
			(layers "*.Cu" "*.Mask")
			(remove_unused_layers no)
			(net "GND")
			(clearance 0.1651)
			(thermal_gap 0.1651)
		)
		(pad "GND38" thru_hole circle
			(at 17.999964 9.700006 270)
			(size 0.762 0.762)
			(drill 0.359918)
			(layers "*.Cu" "*.Mask")
			(remove_unused_layers no)
			(net "GND")
			(clearance 0.1651)
			(thermal_gap 0.1651)
		)
		(pad "GND39" thru_hole circle
			(at 19.800062 -0.100076 270)
			(size 0.762 0.762)
			(drill 0.359918)
			(layers "*.Cu" "*.Mask")
			(remove_unused_layers no)
			(net "GND")
			(clearance 0.1651)
			(thermal_gap 0.1651)
		)
		(pad "GND40" thru_hole circle
			(at 19.800062 3.50012 270)
			(size 0.762 0.762)
			(drill 0.359918)
			(layers "*.Cu" "*.Mask")
			(remove_unused_layers no)
			(net "GND")
			(clearance 0.1651)
			(thermal_gap 0.1651)
		)
		(pad "GND41" thru_hole circle
			(at 19.800062 7.100062 270)
			(size 0.762 0.762)
			(drill 0.359918)
			(layers "*.Cu" "*.Mask")
			(remove_unused_layers no)
			(net "GND")
			(clearance 0.1651)
			(thermal_gap 0.1651)
		)
		(pad "GND42" thru_hole circle
			(at 19.800062 10.700004 270)
			(size 0.762 0.762)
			(drill 0.359918)
			(layers "*.Cu" "*.Mask")
			(remove_unused_layers no)
			(net "GND")
			(clearance 0.1651)
			(thermal_gap 0.1651)
		)
		(pad "GND43" thru_hole circle
			(at 21.599906 2.500122 270)
			(size 0.762 0.762)
			(drill 0.359918)
			(layers "*.Cu" "*.Mask")
			(remove_unused_layers no)
			(net "GND")
			(clearance 0.1651)
			(thermal_gap 0.1651)
		)
		(pad "GND44" thru_hole circle
			(at 21.599906 6.100064 270)
			(size 0.762 0.762)
			(drill 0.359918)
			(layers "*.Cu" "*.Mask")
			(remove_unused_layers no)
			(net "GND")
			(clearance 0.1651)
			(thermal_gap 0.1651)
		)
		(pad "GND45" thru_hole circle
			(at 21.599906 9.700006 270)
			(size 0.762 0.762)
			(drill 0.359918)
			(layers "*.Cu" "*.Mask")
			(remove_unused_layers no)
			(net "GND")
			(clearance 0.1651)
			(thermal_gap 0.1651)
		)
		(pad "GND46" thru_hole circle
			(at 23.400004 -0.100076 270)
			(size 0.762 0.762)
			(drill 0.359918)
			(layers "*.Cu" "*.Mask")
			(remove_unused_layers no)
			(net "GND")
			(clearance 0.1651)
			(thermal_gap 0.1651)
		)
		(pad "GND47" thru_hole circle
			(at 23.400004 3.50012 270)
			(size 0.762 0.762)
			(drill 0.359918)
			(layers "*.Cu" "*.Mask")
			(remove_unused_layers no)
			(net "GND")
			(clearance 0.1651)
			(thermal_gap 0.1651)
		)
		(pad "GND48" thru_hole circle
			(at 23.400004 7.100062 270)
			(size 0.762 0.762)
			(drill 0.359918)
			(layers "*.Cu" "*.Mask")
			(remove_unused_layers no)
			(net "GND")
			(clearance 0.1651)
			(thermal_gap 0.1651)
		)
		(pad "GND49" thru_hole circle
			(at 23.400004 10.700004 270)
			(size 0.762 0.762)
			(drill 0.359918)
			(layers "*.Cu" "*.Mask")
			(remove_unused_layers no)
			(net "GND")
			(clearance 0.1651)
			(thermal_gap 0.1651)
		)
		(pad "GND50" thru_hole circle
			(at 25.200102 2.500122 270)
			(size 0.762 0.762)
			(drill 0.359918)
			(layers "*.Cu" "*.Mask")
			(remove_unused_layers no)
			(net "GND")
			(clearance 0.1651)
			(thermal_gap 0.1651)
		)
		(pad "GND51" thru_hole circle
			(at 25.200102 6.100064 270)
			(size 0.762 0.762)
			(drill 0.359918)
			(layers "*.Cu" "*.Mask")
			(remove_unused_layers no)
			(net "GND")
			(clearance 0.1651)
			(thermal_gap 0.1651)
		)
		(pad "GND52" thru_hole circle
			(at 25.200102 9.700006 270)
			(size 0.762 0.762)
			(drill 0.359918)
			(layers "*.Cu" "*.Mask")
			(remove_unused_layers no)
			(net "GND")
			(clearance 0.1651)
			(thermal_gap 0.1651)
		)
		(pad "GND53" thru_hole circle
			(at 26.999946 -0.100076 270)
			(size 0.762 0.762)
			(drill 0.359918)
			(layers "*.Cu" "*.Mask")
			(remove_unused_layers no)
			(net "GND")
			(clearance 0.1651)
			(thermal_gap 0.1651)
		)
		(pad "GND54" thru_hole circle
			(at 26.999946 3.50012 270)
			(size 0.762 0.762)
			(drill 0.359918)
			(layers "*.Cu" "*.Mask")
			(remove_unused_layers no)
			(net "GND")
			(clearance 0.1651)
			(thermal_gap 0.1651)
		)
		(pad "GND55" thru_hole circle
			(at 26.999946 7.100062 270)
			(size 0.762 0.762)
			(drill 0.359918)
			(layers "*.Cu" "*.Mask")
			(remove_unused_layers no)
			(net "GND")
			(clearance 0.1651)
			(thermal_gap 0.1651)
		)
		(pad "GND56" thru_hole circle
			(at 26.999946 10.700004 270)
			(size 0.762 0.762)
			(drill 0.359918)
			(layers "*.Cu" "*.Mask")
			(remove_unused_layers no)
			(net "GND")
			(clearance 0.1651)
			(thermal_gap 0.1651)
		)
		(pad "GND57" thru_hole circle
			(at 28.800044 2.500122 270)
			(size 0.762 0.762)
			(drill 0.359918)
			(layers "*.Cu" "*.Mask")
			(remove_unused_layers no)
			(net "GND")
			(clearance 0.1651)
			(thermal_gap 0.1651)
		)
		(pad "GND58" thru_hole circle
			(at 28.800044 6.100064 270)
			(size 0.762 0.762)
			(drill 0.359918)
			(layers "*.Cu" "*.Mask")
			(remove_unused_layers no)
			(net "GND")
			(clearance 0.1651)
			(thermal_gap 0.1651)
		)
		(pad "GND59" thru_hole circle
			(at 28.800044 9.700006 270)
			(size 0.762 0.762)
			(drill 0.359918)
			(layers "*.Cu" "*.Mask")
			(remove_unused_layers no)
			(net "GND")
			(clearance 0.1651)
			(thermal_gap 0.1651)
		)
		(pad "GND60" thru_hole circle
			(at 30.599888 -0.100076 270)
			(size 0.762 0.762)
			(drill 0.359918)
			(layers "*.Cu" "*.Mask")
			(remove_unused_layers no)
			(net "GND")
			(clearance 0.1651)
			(thermal_gap 0.1651)
		)
		(pad "GND61" thru_hole circle
			(at 30.599888 3.50012 270)
			(size 0.762 0.762)
			(drill 0.359918)
			(layers "*.Cu" "*.Mask")
			(remove_unused_layers no)
			(net "GND")
			(clearance 0.1651)
			(thermal_gap 0.1651)
		)
		(pad "GND62" thru_hole circle
			(at 30.599888 7.100062 270)
			(size 0.762 0.762)
			(drill 0.359918)
			(layers "*.Cu" "*.Mask")
			(remove_unused_layers no)
			(net "GND")
			(clearance 0.1651)
			(thermal_gap 0.1651)
		)
		(pad "GND63" thru_hole circle
			(at 30.599888 10.700004 270)
			(size 0.762 0.762)
			(drill 0.359918)
			(layers "*.Cu" "*.Mask")
			(remove_unused_layers no)
			(net "GND")
			(clearance 0.1651)
			(thermal_gap 0.1651)
		)
		(pad "GND64" thru_hole circle
			(at 32.399986 2.500122 270)
			(size 0.762 0.762)
			(drill 0.359918)
			(layers "*.Cu" "*.Mask")
			(remove_unused_layers no)
			(net "GND")
			(clearance 0.1651)
			(thermal_gap 0.1651)
		)
		(pad "GND65" thru_hole circle
			(at 32.399986 6.100064 270)
			(size 0.762 0.762)
			(drill 0.359918)
			(layers "*.Cu" "*.Mask")
			(remove_unused_layers no)
			(net "GND")
			(clearance 0.1651)
			(thermal_gap 0.1651)
		)
		(pad "GND66" thru_hole circle
			(at 32.399986 9.700006 270)
			(size 0.762 0.762)
			(drill 0.359918)
			(layers "*.Cu" "*.Mask")
			(remove_unused_layers no)
			(net "GND")
			(clearance 0.1651)
			(thermal_gap 0.1651)
		)
		(pad "GND67" thru_hole circle
			(at 34.200084 -0.100076 270)
			(size 0.762 0.762)
			(drill 0.359918)
			(layers "*.Cu" "*.Mask")
			(remove_unused_layers no)
			(net "GND")
			(clearance 0.1651)
			(thermal_gap 0.1651)
		)
		(pad "GND68" thru_hole circle
			(at 34.200084 3.50012 270)
			(size 0.762 0.762)
			(drill 0.359918)
			(layers "*.Cu" "*.Mask")
			(remove_unused_layers no)
			(net "GND")
			(clearance 0.1651)
			(thermal_gap 0.1651)
		)
		(pad "GND69" thru_hole circle
			(at 34.200084 7.100062 270)
			(size 0.762 0.762)
			(drill 0.359918)
			(layers "*.Cu" "*.Mask")
			(remove_unused_layers no)
			(net "GND")
			(clearance 0.1651)
			(thermal_gap 0.1651)
		)
		(pad "GND70" thru_hole circle
			(at 34.200084 10.700004 270)
			(size 0.762 0.762)
			(drill 0.359918)
			(layers "*.Cu" "*.Mask")
			(remove_unused_layers no)
			(net "GND")
			(clearance 0.1651)
			(thermal_gap 0.1651)
		)
		(pad "GND71" thru_hole circle
			(at 35.999928 2.500122 270)
			(size 0.762 0.762)
			(drill 0.359918)
			(layers "*.Cu" "*.Mask")
			(remove_unused_layers no)
			(net "GND")
			(clearance 0.1651)
			(thermal_gap 0.1651)
		)
		(pad "GND72" thru_hole circle
			(at 35.999928 6.100064 270)
			(size 0.762 0.762)
			(drill 0.359918)
			(layers "*.Cu" "*.Mask")
			(remove_unused_layers no)
			(net "GND")
			(clearance 0.1651)
			(thermal_gap 0.1651)
		)
		(pad "GND73" thru_hole circle
			(at 35.999928 9.700006 270)
			(size 0.762 0.762)
			(drill 0.359918)
			(layers "*.Cu" "*.Mask")
			(remove_unused_layers no)
			(net "GND")
			(clearance 0.1651)
			(thermal_gap 0.1651)
		)
		(pad "GND74" thru_hole circle
			(at 37.800026 -0.100076 270)
			(size 0.762 0.762)
			(drill 0.359918)
			(layers "*.Cu" "*.Mask")
			(remove_unused_layers no)
			(net "GND")
			(clearance 0.1651)
			(thermal_gap 0.1651)
		)
	)
)
